# T6G (Grand Teton) — schematic netlist excerpt (pin names and nets, part order shuffled) for the footprints in the layout excerpt that follows; sources: Cadence DE-HDL packaged netlist, KiCad conversion of 04192023_DAF0TMB3IC0_F0TG_MB_C_brd_V02_OCP.brd

R4145  Q_RES  33.2 1% CHIP  pkg 0402LF  page 80 : A = PRSNT_CABLE_GPU_B3_ISO_R_N ; B = PRSNT_CABLE_GPU_B3_ISO_N
R1654  Q_RES  1K 1% CHIP  pkg 0402LF  page 188 : A = VR_P5V_EN_D_R ; B = VR_P5V_EN_D_R1

(kicad_pcb
	(version 20260206)
	(generator "pcbnew")
	(generator_version "10.0")
	(general
		(thickness 1.6)
		(legacy_teardrops no)
	)
	(paper "A4")
	(title_block
		(title "04192023_DAF0TMB3IC0_F0TG_MB_C_brd_V02_OCP.brd")
		(comment 1 "Grand Teton / footprints 3374-3375 of 8354")
	)
	(layers
		(0 "F.Cu" signal "TOP")
		(4 "In1.Cu" signal "GND")
		(6 "In2.Cu" signal "IN1")
		(8 "In3.Cu" signal "GND1")
		(10 "In4.Cu" signal "IN2")
		(12 "In5.Cu" signal "GND2")
		(14 "In6.Cu" signal "IN3")
		(16 "In7.Cu" signal "GND3")
		(18 "In8.Cu" signal "VCC")
		(20 "In9.Cu" signal "VCC1")
		(22 "In10.Cu" signal "GND4")
		(24 "In11.Cu" signal "IN4")
		(26 "In12.Cu" signal "GND5")
		(28 "In13.Cu" signal "IN5")
		(30 "In14.Cu" signal "GND6")
		(32 "In15.Cu" signal "IN6")
		(34 "In16.Cu" signal "GND7")
		(2 "B.Cu" signal "BOTTOM")
		(9 "F.Adhes" user "F.Adhesive")
		(11 "B.Adhes" user "B.Adhesive")
		(13 "F.Paste" user "Package Geometry/Pastemask Top")
		(15 "B.Paste" user "Package Geometry/Pastemask Bottom")
		(5 "F.SilkS" user "Ref Des/Silkscreen Top")
		(7 "B.SilkS" user "Ref Des/Silkscreen Bottom")
		(1 "F.Mask" user "Board Geometry/Soldermask Top")
		(3 "B.Mask" user "Board Geometry/Soldermask Bottom")
		(17 "Dwgs.User" user "User.Drawings")
		(19 "Cmts.User" user "User.Comments")
		(21 "Eco1.User" user "User.Eco1")
		(23 "Eco2.User" user "User.Eco2")
		(25 "Edge.Cuts" user "Board Geometry/Outline")
		(27 "Margin" user)
		(31 "F.CrtYd" user "Package Geometry/Place Bound Top")
		(29 "B.CrtYd" user "Package Geometry/Place Bound Bottom")
		(35 "F.Fab" user "Ref Des/Assembly Top")
		(33 "B.Fab" user "Ref Des/Assembly Bottom")
	)
	(footprint ""
		(layer "F.Cu")
		(at 148.499068 -109.721904 180)
		(property "Reference" "R1654"
			(at 0 0 180)
			(layer "F.SilkS")
			(hide yes)
			(effects
				(font
					(size 1.27 1.27)
				)
			)
		)
		(property "Value" ""
			(at 0 0 180)
			(layer "F.Fab")
			(effects
				(font
					(size 1.27 1.27)
				)
			)
		)
		(duplicate_pad_numbers_are_jumpers no)
		(fp_line
			(start 0.7874 0.4064)
			(end -0.7874 0.4064)
			(stroke
				(width 0.1524)
				(type default)
			)
			(layer "F.SilkS")
		)
		(fp_line
			(start 0.7874 -0.4064)
			(end 0.7874 0.4064)
			(stroke
				(width 0.1524)
				(type default)
			)
			(layer "F.SilkS")
		)
		(fp_line
			(start -0.7874 0.4064)
			(end -0.7874 -0.4064)
			(stroke
				(width 0.1524)
				(type default)
			)
			(layer "F.SilkS")
		)
		(fp_line
			(start -0.7874 -0.4064)
			(end 0.7874 -0.4064)
			(stroke
				(width 0.1524)
				(type default)
			)
			(layer "F.SilkS")
		)
		(fp_line
			(start 0.67945 0.3048)
			(end 0.120396 0.3048)
			(stroke
				(width 0.1)
				(type default)
			)
			(layer "F.Fab")
		)
		(fp_line
			(start 0.67945 -0.3048)
			(end 0.67945 0.3048)
			(stroke
				(width 0.1)
				(type default)
			)
			(layer "F.Fab")
		)
		(fp_line
			(start 0.12065 -0.2794)
			(end 0.12065 -0.3048)
			(stroke
				(width 0.1)
				(type default)
			)
			(layer "F.Fab")
		)
		(fp_line
			(start 0.12065 -0.3048)
			(end 0.67945 -0.3048)
			(stroke
				(width 0.1)
				(type default)
			)
			(layer "F.Fab")
		)
		(fp_line
			(start 0.120396 0.3048)
			(end 0.120396 0.2794)
			(stroke
				(width 0.1)
				(type default)
			)
			(layer "F.Fab")
		)
		(fp_line
			(start 0.120396 0.2794)
			(end -0.12065 0.2794)
			(stroke
				(width 0.1)
				(type default)
			)
			(layer "F.Fab")
		)
		(fp_line
			(start -0.12065 0.3048)
			(end -0.67945 0.3048)
			(stroke
				(width 0.1)
				(type default)
			)
			(layer "F.Fab")
		)
		(fp_line
			(start -0.12065 0.2794)
			(end -0.12065 0.3048)
			(stroke
				(width 0.1)
				(type default)
			)
			(layer "F.Fab")
		)
		(fp_line
			(start -0.12065 -0.2794)
			(end 0.12065 -0.2794)
			(stroke
				(width 0.1)
				(type default)
			)
			(layer "F.Fab")
		)
		(fp_line
			(start -0.12065 -0.305054)
			(end -0.12065 -0.2794)
			(stroke
				(width 0.1)
				(type default)
			)
			(layer "F.Fab")
		)
		(fp_line
			(start -0.67945 0.3048)
			(end -0.67945 -0.305054)
			(stroke
				(width 0.1)
				(type default)
			)
			(layer "F.Fab")
		)
		(fp_line
			(start -0.67945 -0.305054)
			(end -0.12065 -0.305054)
			(stroke
				(width 0.1)
				(type default)
			)
			(layer "F.Fab")
		)
		(pad "1" smd circle
			(at -0.40005 0 180)
			(size 0 0)
			(layers "F.Cu" "F.Mask" "F.Paste")
			(net "VR_P5V_EN_D_R")
		)
		(pad "2" smd circle
			(at 0.40005 0 180)
			(size 0 0)
			(layers "F.Cu" "F.Mask" "F.Paste")
			(net "VR_P5V_EN_D_R1")
		)
	)
	(footprint ""
		(layer "F.Cu")
		(at 174.57674 -129.377948 90)
		(property "Reference" "R4145"
			(at 0 0 90)
			(layer "F.SilkS")
			(hide yes)
			(effects
				(font
					(size 1.27 1.27)
				)
			)
		)
		(property "Value" ""
			(at 0 0 90)
			(layer "F.Fab")
			(effects
				(font
					(size 1.27 1.27)
				)
			)
		)
		(duplicate_pad_numbers_are_jumpers no)
		(fp_line
			(start 0.7874 -0.4064)
			(end 0.7874 0.4064)
			(stroke
				(width 0.1524)
				(type default)
			)
			(layer "F.SilkS")
		)
		(fp_line
			(start -0.7874 -0.4064)
			(end 0.7874 -0.4064)
			(stroke
				(width 0.1524)
				(type default)
			)
			(layer "F.SilkS")
		)
		(fp_line
			(start 0.7874 0.4064)
			(end -0.7874 0.4064)
			(stroke
				(width 0.1524)
				(type default)
			)
			(layer "F.SilkS")
		)
		(fp_line
			(start -0.7874 0.4064)
			(end -0.7874 -0.4064)
			(stroke
				(width 0.1524)
				(type default)
			)
			(layer "F.SilkS")
		)
		(fp_line
			(start -0.12065 -0.305054)
			(end -0.12065 -0.2794)
			(stroke
				(width 0.1)
				(type default)
			)
			(layer "F.Fab")
		)
		(fp_line
			(start -0.67945 -0.305054)
			(end -0.12065 -0.305054)
			(stroke
				(width 0.1)
				(type default)
			)
			(layer "F.Fab")
		)
		(fp_line
			(start 0.67945 -0.3048)
			(end 0.67945 0.3048)
			(stroke
				(width 0.1)
				(type default)
			)
			(layer "F.Fab")
		)
		(fp_line
			(start 0.12065 -0.3048)
			(end 0.67945 -0.3048)
			(stroke
				(width 0.1)
				(type default)
			)
			(layer "F.Fab")
		)
		(fp_line
			(start 0.12065 -0.2794)
			(end 0.12065 -0.3048)
			(stroke
				(width 0.1)
				(type default)
			)
			(layer "F.Fab")
		)
		(fp_line
			(start -0.12065 -0.2794)
			(end 0.12065 -0.2794)
			(stroke
				(width 0.1)
				(type default)
			)
			(layer "F.Fab")
		)
		(fp_line
			(start 0.120396 0.2794)
			(end -0.12065 0.2794)
			(stroke
				(width 0.1)
				(type default)
			)
			(layer "F.Fab")
		)
		(fp_line
			(start -0.12065 0.2794)
			(end -0.12065 0.3048)
			(stroke
				(width 0.1)
				(type default)
			)
			(layer "F.Fab")
		)
		(fp_line
			(start 0.67945 0.3048)
			(end 0.120396 0.3048)
			(stroke
				(width 0.1)
				(type default)
			)
			(layer "F.Fab")
		)
		(fp_line
			(start 0.120396 0.3048)
			(end 0.120396 0.2794)
			(stroke
				(width 0.1)
				(type default)
			)
			(layer "F.Fab")
		)
		(fp_line
			(start -0.12065 0.3048)
			(end -0.67945 0.3048)
			(stroke
				(width 0.1)
				(type default)
			)
			(layer "F.Fab")
		)
		(fp_line
			(start -0.67945 0.3048)
			(end -0.67945 -0.305054)
			(stroke
				(width 0.1)
				(type default)
			)
			(layer "F.Fab")
		)
		(pad "1" smd circle
			(at -0.40005 0 90)
			(size 0 0)
			(layers "F.Cu" "F.Mask" "F.Paste")
			(net "PRSNT_CABLE_GPU_B3_ISO_R_N")
		)
		(pad "2" smd circle
			(at 0.40005 0 90)
			(size 0 0)
			(layers "F.Cu" "F.Mask" "F.Paste")
			(net "PRSNT_CABLE_GPU_B3_ISO_N")
		)
	)
)
